# T6G (Grand Teton) — schematic netlist excerpt (pin names and nets, part order shuffled) for the footprints in the layout excerpt that follows; sources: Cadence DE-HDL packaged netlist, KiCad conversion of 04192023_DAF0TMB3IC0_F0TG_MB_C_brd_V02_OCP.brd

R3467  Q_RES  10K 1% CHIP  pkg 0402LF  page 128 : A = RST_PERST_0_SWB_BUF_R_N ; B = GND
R3290  Q_RES  1K 1% EMPTY  pkg 0402LF  page 111 : A = FM_P2E_SWA ; B = GND

(kicad_pcb
	(version 20260206)
	(generator "pcbnew")
	(generator_version "10.0")
	(general
		(thickness 1.6)
		(legacy_teardrops no)
	)
	(paper "A4")
	(title_block
		(title "04192023_DAF0TMB3IC0_F0TG_MB_C_brd_V02_OCP.brd")
		(comment 1 "Grand Teton / footprints 2346-2347 of 8354")
	)
	(layers
		(0 "F.Cu" signal "TOP")
		(4 "In1.Cu" signal "GND")
		(6 "In2.Cu" signal "IN1")
		(8 "In3.Cu" signal "GND1")
		(10 "In4.Cu" signal "IN2")
		(12 "In5.Cu" signal "GND2")
		(14 "In6.Cu" signal "IN3")
		(16 "In7.Cu" signal "GND3")
		(18 "In8.Cu" signal "VCC")
		(20 "In9.Cu" signal "VCC1")
		(22 "In10.Cu" signal "GND4")
		(24 "In11.Cu" signal "IN4")
		(26 "In12.Cu" signal "GND5")
		(28 "In13.Cu" signal "IN5")
		(30 "In14.Cu" signal "GND6")
		(32 "In15.Cu" signal "IN6")
		(34 "In16.Cu" signal "GND7")
		(2 "B.Cu" signal "BOTTOM")
		(9 "F.Adhes" user "F.Adhesive")
		(11 "B.Adhes" user "B.Adhesive")
		(13 "F.Paste" user "Package Geometry/Pastemask Top")
		(15 "B.Paste" user "Package Geometry/Pastemask Bottom")
		(5 "F.SilkS" user "Ref Des/Silkscreen Top")
		(7 "B.SilkS" user "Ref Des/Silkscreen Bottom")
		(1 "F.Mask" user "Board Geometry/Soldermask Top")
		(3 "B.Mask" user "Board Geometry/Soldermask Bottom")
		(17 "Dwgs.User" user "User.Drawings")
		(19 "Cmts.User" user "User.Comments")
		(21 "Eco1.User" user "User.Eco1")
		(23 "Eco2.User" user "User.Eco2")
		(25 "Edge.Cuts" user "Board Geometry/Outline")
		(27 "Margin" user)
		(31 "F.CrtYd" user "Package Geometry/Place Bound Top")
		(29 "B.CrtYd" user "Package Geometry/Place Bound Bottom")
		(35 "F.Fab" user "Ref Des/Assembly Top")
		(33 "B.Fab" user "Ref Des/Assembly Bottom")
	)
	(footprint ""
		(layer "F.Cu")
		(at 50.616866 -437.642 180)
		(property "Reference" "R3467"
			(at 0 0 180)
			(layer "F.SilkS")
			(hide yes)
			(effects
				(font
					(size 1.27 1.27)
				)
			)
		)
		(property "Value" ""
			(at 0 0 180)
			(layer "F.Fab")
			(effects
				(font
					(size 1.27 1.27)
				)
			)
		)
		(duplicate_pad_numbers_are_jumpers no)
		(fp_line
			(start 0.7874 0.4064)
			(end -0.7874 0.4064)
			(stroke
				(width 0.1524)
				(type default)
			)
			(layer "F.SilkS")
		)
		(fp_line
			(start 0.7874 -0.4064)
			(end 0.7874 0.4064)
			(stroke
				(width 0.1524)
				(type default)
			)
			(layer "F.SilkS")
		)
		(fp_line
			(start -0.7874 0.4064)
			(end -0.7874 -0.4064)
			(stroke
				(width 0.1524)
				(type default)
			)
			(layer "F.SilkS")
		)
		(fp_line
			(start -0.7874 -0.4064)
			(end 0.7874 -0.4064)
			(stroke
				(width 0.1524)
				(type default)
			)
			(layer "F.SilkS")
		)
		(fp_line
			(start 0.67945 0.3048)
			(end 0.120396 0.3048)
			(stroke
				(width 0.1)
				(type default)
			)
			(layer "F.Fab")
		)
		(fp_line
			(start 0.67945 -0.3048)
			(end 0.67945 0.3048)
			(stroke
				(width 0.1)
				(type default)
			)
			(layer "F.Fab")
		)
		(fp_line
			(start 0.12065 -0.2794)
			(end 0.12065 -0.3048)
			(stroke
				(width 0.1)
				(type default)
			)
			(layer "F.Fab")
		)
		(fp_line
			(start 0.12065 -0.3048)
			(end 0.67945 -0.3048)
			(stroke
				(width 0.1)
				(type default)
			)
			(layer "F.Fab")
		)
		(fp_line
			(start 0.120396 0.3048)
			(end 0.120396 0.2794)
			(stroke
				(width 0.1)
				(type default)
			)
			(layer "F.Fab")
		)
		(fp_line
			(start 0.120396 0.2794)
			(end -0.12065 0.2794)
			(stroke
				(width 0.1)
				(type default)
			)
			(layer "F.Fab")
		)
		(fp_line
			(start -0.12065 0.3048)
			(end -0.67945 0.3048)
			(stroke
				(width 0.1)
				(type default)
			)
			(layer "F.Fab")
		)
		(fp_line
			(start -0.12065 0.2794)
			(end -0.12065 0.3048)
			(stroke
				(width 0.1)
				(type default)
			)
			(layer "F.Fab")
		)
		(fp_line
			(start -0.12065 -0.2794)
			(end 0.12065 -0.2794)
			(stroke
				(width 0.1)
				(type default)
			)
			(layer "F.Fab")
		)
		(fp_line
			(start -0.12065 -0.305054)
			(end -0.12065 -0.2794)
			(stroke
				(width 0.1)
				(type default)
			)
			(layer "F.Fab")
		)
		(fp_line
			(start -0.67945 0.3048)
			(end -0.67945 -0.305054)
			(stroke
				(width 0.1)
				(type default)
			)
			(layer "F.Fab")
		)
		(fp_line
			(start -0.67945 -0.305054)
			(end -0.12065 -0.305054)
			(stroke
				(width 0.1)
				(type default)
			)
			(layer "F.Fab")
		)
		(pad "1" smd circle
			(at -0.40005 0 180)
			(size 0 0)
			(layers "F.Cu" "F.Mask" "F.Paste")
			(net "RST_PERST_0_SWB_BUF_R_N")
		)
		(pad "2" smd circle
			(at 0.40005 0 180)
			(size 0 0)
			(layers "F.Cu" "F.Mask" "F.Paste")
			(net "GND")
		)
	)
	(footprint ""
		(layer "F.Cu")
		(at 35.649662 -419.249098 -90)
		(property "Reference" "R3290"
			(at 0 0 270)
			(layer "F.SilkS")
			(hide yes)
			(effects
				(font
					(size 1.27 1.27)
				)
			)
		)
		(property "Value" ""
			(at 0 0 270)
			(layer "F.Fab")
			(effects
				(font
					(size 1.27 1.27)
				)
			)
		)
		(duplicate_pad_numbers_are_jumpers no)
		(fp_line
			(start -0.7874 0.4064)
			(end -0.7874 -0.4064)
			(stroke
				(width 0.1524)
				(type default)
			)
			(layer "F.SilkS")
		)
		(fp_line
			(start 0.7874 0.4064)
			(end -0.7874 0.4064)
			(stroke
				(width 0.1524)
				(type default)
			)
			(layer "F.SilkS")
		)
		(fp_line
			(start -0.7874 -0.4064)
			(end 0.7874 -0.4064)
			(stroke
				(width 0.1524)
				(type default)
			)
			(layer "F.SilkS")
		)
		(fp_line
			(start 0.7874 -0.4064)
			(end 0.7874 0.4064)
			(stroke
				(width 0.1524)
				(type default)
			)
			(layer "F.SilkS")
		)
		(fp_line
			(start -0.67945 0.3048)
			(end -0.67945 -0.305054)
			(stroke
				(width 0.1)
				(type default)
			)
			(layer "F.Fab")
		)
		(fp_line
			(start -0.12065 0.3048)
			(end -0.67945 0.3048)
			(stroke
				(width 0.1)
				(type default)
			)
			(layer "F.Fab")
		)
		(fp_line
			(start 0.120396 0.3048)
			(end 0.120396 0.2794)
			(stroke
				(width 0.1)
				(type default)
			)
			(layer "F.Fab")
		)
		(fp_line
			(start 0.67945 0.3048)
			(end 0.120396 0.3048)
			(stroke
				(width 0.1)
				(type default)
			)
			(layer "F.Fab")
		)
		(fp_line
			(start -0.12065 0.2794)
			(end -0.12065 0.3048)
			(stroke
				(width 0.1)
				(type default)
			)
			(layer "F.Fab")
		)
		(fp_line
			(start 0.120396 0.2794)
			(end -0.12065 0.2794)
			(stroke
				(width 0.1)
				(type default)
			)
			(layer "F.Fab")
		)
		(fp_line
			(start -0.12065 -0.2794)
			(end 0.12065 -0.2794)
			(stroke
				(width 0.1)
				(type default)
			)
			(layer "F.Fab")
		)
		(fp_line
			(start 0.12065 -0.2794)
			(end 0.12065 -0.3048)
			(stroke
				(width 0.1)
				(type default)
			)
			(layer "F.Fab")
		)
		(fp_line
			(start 0.12065 -0.3048)
			(end 0.67945 -0.3048)
			(stroke
				(width 0.1)
				(type default)
			)
			(layer "F.Fab")
		)
		(fp_line
			(start 0.67945 -0.3048)
			(end 0.67945 0.3048)
			(stroke
				(width 0.1)
				(type default)
			)
			(layer "F.Fab")
		)
		(fp_line
			(start -0.67945 -0.305054)
			(end -0.12065 -0.305054)
			(stroke
				(width 0.1)
				(type default)
			)
			(layer "F.Fab")
		)
		(fp_line
			(start -0.12065 -0.305054)
			(end -0.12065 -0.2794)
			(stroke
				(width 0.1)
				(type default)
			)
			(layer "F.Fab")
		)
		(pad "1" smd circle
			(at -0.40005 0 270)
			(size 0 0)
			(layers "F.Cu" "F.Mask" "F.Paste")
			(net "FM_P2E_SWA")
		)
		(pad "2" smd circle
			(at 0.40005 0 270)
			(size 0 0)
			(layers "F.Cu" "F.Mask" "F.Paste")
			(net "GND")
		)
	)
)
